(kicad_pcb
	(version 20260206)
	(generator "pcbnew")
	(generator_version "10.0")
	(general
		(thickness 1.6)
		(legacy_teardrops no)
	)
	(paper "A4")
	(title_block
		(title "04192023_DAF0TMB3IC0_F0TG_MB_C_brd_V02_OCP.brd")
		(comment 1 "Grand Teton / footprints 1368-1375 of 8354")
	)
	(layers
		(0 "F.Cu" signal "TOP")
		(4 "In1.Cu" signal "GND")
		(6 "In2.Cu" signal "IN1")
		(8 "In3.Cu" signal "GND1")
		(10 "In4.Cu" signal "IN2")
		(12 "In5.Cu" signal "GND2")
		(14 "In6.Cu" signal "IN3")
		(16 "In7.Cu" signal "GND3")
		(18 "In8.Cu" signal "VCC")
		(20 "In9.Cu" signal "VCC1")
		(22 "In10.Cu" signal "GND4")
		(24 "In11.Cu" signal "IN4")
		(26 "In12.Cu" signal "GND5")
		(28 "In13.Cu" signal "IN5")
		(30 "In14.Cu" signal "GND6")
		(32 "In15.Cu" signal "IN6")
		(34 "In16.Cu" signal "GND7")
		(2 "B.Cu" signal "BOTTOM")
		(9 "F.Adhes" user "F.Adhesive")
		(11 "B.Adhes" user "B.Adhesive")
		(13 "F.Paste" user "Package Geometry/Pastemask Top")
		(15 "B.Paste" user "Package Geometry/Pastemask Bottom")
		(5 "F.SilkS" user "Ref Des/Silkscreen Top")
		(7 "B.SilkS" user "Ref Des/Silkscreen Bottom")
		(1 "F.Mask" user "Board Geometry/Soldermask Top")
		(3 "B.Mask" user "Board Geometry/Soldermask Bottom")
		(17 "Dwgs.User" user "User.Drawings")
		(19 "Cmts.User" user "User.Comments")
		(21 "Eco1.User" user "User.Eco1")
		(23 "Eco2.User" user "User.Eco2")
		(25 "Edge.Cuts" user "Board Geometry/Outline")
		(27 "Margin" user)
		(31 "F.CrtYd" user "Package Geometry/Place Bound Top")
		(29 "B.CrtYd" user "Package Geometry/Place Bound Bottom")
		(35 "F.Fab" user "Ref Des/Assembly Top")
		(33 "B.Fab" user "Ref Des/Assembly Bottom")
	)
	(footprint ""
		(layer "F.Cu")
		(at 340.026244 -378.95403 -90)
		(property "Reference" "C953"
			(at 0 0 270)
			(layer "F.SilkS")
			(hide yes)
			(effects
				(font
					(size 1.27 1.27)
				)
			)
		)
		(property "Value" ""
			(at 0 0 270)
			(layer "F.Fab")
			(effects
				(font
					(size 1.27 1.27)
				)
			)
		)
		(duplicate_pad_numbers_are_jumpers no)
		(fp_line
			(start -0.299974 0.150114)
			(end -0.299974 -0.150114)
			(stroke
				(width 0.1)
				(type default)
			)
			(layer "F.Fab")
		)
		(fp_line
			(start 0.299974 0.150114)
			(end -0.299974 0.150114)
			(stroke
				(width 0.1)
				(type default)
			)
			(layer "F.Fab")
		)
		(fp_line
			(start -0.299974 -0.150114)
			(end 0.299974 -0.150114)
			(stroke
				(width 0.1)
				(type default)
			)
			(layer "F.Fab")
		)
		(fp_line
			(start 0.299974 -0.150114)
			(end 0.299974 0.150114)
			(stroke
				(width 0.1)
				(type default)
			)
			(layer "F.Fab")
		)
		(pad "1" smd rect
			(at -0.2667 0 270)
			(size 0.3048 0.381)
			(layers "F.Cu" "F.Mask" "F.Paste")
			(net "P5E_CPU0_P1_TX_C_DP<6>")
		)
		(pad "2" smd rect
			(at 0.2667 0 270)
			(size 0.3048 0.381)
			(layers "F.Cu" "F.Mask" "F.Paste")
			(net "P5E_CPU0_P1_TX_DP<6>")
		)
	)
	(footprint ""
		(layer "F.Cu")
		(at 148.637244 -375.49963 -90)
		(property "Reference" "C764"
			(at 0 0 270)
			(layer "F.SilkS")
			(hide yes)
			(effects
				(font
					(size 1.27 1.27)
				)
			)
		)
		(property "Value" ""
			(at 0 0 270)
			(layer "F.Fab")
			(effects
				(font
					(size 1.27 1.27)
				)
			)
		)
		(duplicate_pad_numbers_are_jumpers no)
		(fp_line
			(start -0.299974 0.150114)
			(end -0.299974 -0.150114)
			(stroke
				(width 0.1)
				(type default)
			)
			(layer "F.Fab")
		)
		(fp_line
			(start 0.299974 0.150114)
			(end -0.299974 0.150114)
			(stroke
				(width 0.1)
				(type default)
			)
			(layer "F.Fab")
		)
		(fp_line
			(start -0.299974 -0.150114)
			(end 0.299974 -0.150114)
			(stroke
				(width 0.1)
				(type default)
			)
			(layer "F.Fab")
		)
		(fp_line
			(start 0.299974 -0.150114)
			(end 0.299974 0.150114)
			(stroke
				(width 0.1)
				(type default)
			)
			(layer "F.Fab")
		)
		(pad "1" smd rect
			(at -0.2667 0 270)
			(size 0.3048 0.381)
			(layers "F.Cu" "F.Mask" "F.Paste")
			(net "P5E_CPU1_P2_TX_C_DN<4>")
		)
		(pad "2" smd rect
			(at 0.2667 0 270)
			(size 0.3048 0.381)
			(layers "F.Cu" "F.Mask" "F.Paste")
			(net "P5E_CPU1_P2_TX_DN<4>")
		)
	)
	(footprint ""
		(layer "F.Cu")
		(at 113.440718 -401.280122)
		(property "Reference" "R1199"
			(at 0 0 0)
			(layer "F.SilkS")
			(hide yes)
			(effects
				(font
					(size 1.27 1.27)
				)
			)
		)
		(property "Value" ""
			(at 0 0 0)
			(layer "F.Fab")
			(effects
				(font
					(size 1.27 1.27)
				)
			)
		)
		(duplicate_pad_numbers_are_jumpers no)
		(fp_line
			(start -0.32512 -0.175006)
			(end 0.32512 -0.175006)
			(stroke
				(width 0.1)
				(type default)
			)
			(layer "F.Fab")
		)
		(fp_line
			(start -0.32512 0.175006)
			(end -0.32512 -0.175006)
			(stroke
				(width 0.1)
				(type default)
			)
			(layer "F.Fab")
		)
		(fp_line
			(start 0.32512 -0.175006)
			(end 0.32512 0.175006)
			(stroke
				(width 0.1)
				(type default)
			)
			(layer "F.Fab")
		)
		(fp_line
			(start 0.32512 0.175006)
			(end -0.32512 0.175006)
			(stroke
				(width 0.1)
				(type default)
			)
			(layer "F.Fab")
		)
		(pad "1" smd rect
			(at -0.2667 0)
			(size 0.3048 0.381)
			(layers "F.Cu" "F.Mask" "F.Paste")
			(net "RST_SMB_RT_ROM_R1_N")
		)
		(pad "2" smd rect
			(at 0.2667 0 180)
			(size 0.3048 0.381)
			(layers "F.Cu" "F.Mask" "F.Paste")
			(net "FM_SMB_RT_ROM_MUX2_SEL")
		)
	)
	(footprint ""
		(layer "F.Cu")
		(at 439.029602 -424.80611)
		(property "Reference" "R655"
			(at 0 0 0)
			(layer "F.SilkS")
			(hide yes)
			(effects
				(font
					(size 1.27 1.27)
				)
			)
		)
		(property "Value" ""
			(at 0 0 0)
			(layer "F.Fab")
			(effects
				(font
					(size 1.27 1.27)
				)
			)
		)
		(duplicate_pad_numbers_are_jumpers no)
		(fp_line
			(start -0.7874 -0.4064)
			(end 0.7874 -0.4064)
			(stroke
				(width 0.1524)
				(type default)
			)
			(layer "F.SilkS")
		)
		(fp_line
			(start -0.7874 0.4064)
			(end -0.7874 -0.4064)
			(stroke
				(width 0.1524)
				(type default)
			)
			(layer "F.SilkS")
		)
		(fp_line
			(start 0.7874 -0.4064)
			(end 0.7874 0.4064)
			(stroke
				(width 0.1524)
				(type default)
			)
			(layer "F.SilkS")
		)
		(fp_line
			(start 0.7874 0.4064)
			(end -0.7874 0.4064)
			(stroke
				(width 0.1524)
				(type default)
			)
			(layer "F.SilkS")
		)
		(fp_line
			(start -0.67945 -0.305054)
			(end -0.12065 -0.305054)
			(stroke
				(width 0.1)
				(type default)
			)
			(layer "F.Fab")
		)
		(fp_line
			(start -0.67945 0.3048)
			(end -0.67945 -0.305054)
			(stroke
				(width 0.1)
				(type default)
			)
			(layer "F.Fab")
		)
		(fp_line
			(start -0.12065 -0.305054)
			(end -0.12065 -0.2794)
			(stroke
				(width 0.1)
				(type default)
			)
			(layer "F.Fab")
		)
		(fp_line
			(start -0.12065 -0.2794)
			(end 0.12065 -0.2794)
			(stroke
				(width 0.1)
				(type default)
			)
			(layer "F.Fab")
		)
		(fp_line
			(start -0.12065 0.2794)
			(end -0.12065 0.3048)
			(stroke
				(width 0.1)
				(type default)
			)
			(layer "F.Fab")
		)
		(fp_line
			(start -0.12065 0.3048)
			(end -0.67945 0.3048)
			(stroke
				(width 0.1)
				(type default)
			)
			(layer "F.Fab")
		)
		(fp_line
			(start 0.120396 0.2794)
			(end -0.12065 0.2794)
			(stroke
				(width 0.1)
				(type default)
			)
			(layer "F.Fab")
		)
		(fp_line
			(start 0.120396 0.3048)
			(end 0.120396 0.2794)
			(stroke
				(width 0.1)
				(type default)
			)
			(layer "F.Fab")
		)
		(fp_line
			(start 0.12065 -0.3048)
			(end 0.67945 -0.3048)
			(stroke
				(width 0.1)
				(type default)
			)
			(layer "F.Fab")
		)
		(fp_line
			(start 0.12065 -0.2794)
			(end 0.12065 -0.3048)
			(stroke
				(width 0.1)
				(type default)
			)
			(layer "F.Fab")
		)
		(fp_line
			(start 0.67945 -0.3048)
			(end 0.67945 0.3048)
			(stroke
				(width 0.1)
				(type default)
			)
			(layer "F.Fab")
		)
		(fp_line
			(start 0.67945 0.3048)
			(end 0.120396 0.3048)
			(stroke
				(width 0.1)
				(type default)
			)
			(layer "F.Fab")
		)
		(pad "1" smd circle
			(at -0.40005 0)
			(size 0 0)
			(layers "F.Cu" "F.Mask" "F.Paste")
			(net "P3V3_AUX")
		)
		(pad "2" smd circle
			(at 0.40005 0)
			(size 0 0)
			(layers "F.Cu" "F.Mask" "F.Paste")
			(net "P0V9_RETIMER_CPU0_INALERT")
		)
	)
	(footprint ""
		(layer "F.Cu")
		(at 403.5552 -77.513434 90)
		(property "Reference" "C1860"
			(at 0 0 90)
			(layer "F.SilkS")
			(hide yes)
			(effects
				(font
					(size 1.27 1.27)
				)
			)
		)
		(property "Value" ""
			(at 0 0 90)
			(layer "F.Fab")
			(effects
				(font
					(size 1.27 1.27)
				)
			)
		)
		(duplicate_pad_numbers_are_jumpers no)
		(fp_line
			(start 0.7874 -0.4064)
			(end 0.7874 0.4064)
			(stroke
				(width 0.1524)
				(type default)
			)
			(layer "F.SilkS")
		)
		(fp_line
			(start -0.7874 -0.4064)
			(end 0.7874 -0.4064)
			(stroke
				(width 0.1524)
				(type default)
			)
			(layer "F.SilkS")
		)
		(fp_line
			(start 0.7874 0.4064)
			(end -0.7874 0.4064)
			(stroke
				(width 0.1524)
				(type default)
			)
			(layer "F.SilkS")
		)
		(fp_line
			(start -0.7874 0.4064)
			(end -0.7874 -0.4064)
			(stroke
				(width 0.1524)
				(type default)
			)
			(layer "F.SilkS")
		)
		(fp_line
			(start -0.12065 -0.305054)
			(end -0.12065 -0.2794)
			(stroke
				(width 0.1)
				(type default)
			)
			(layer "F.Fab")
		)
		(fp_line
			(start -0.67945 -0.305054)
			(end -0.12065 -0.305054)
			(stroke
				(width 0.1)
				(type default)
			)
			(layer "F.Fab")
		)
		(fp_line
			(start 0.67945 -0.3048)
			(end 0.67945 0.3048)
			(stroke
				(width 0.1)
				(type default)
			)
			(layer "F.Fab")
		)
		(fp_line
			(start 0.12065 -0.3048)
			(end 0.67945 -0.3048)
			(stroke
				(width 0.1)
				(type default)
			)
			(layer "F.Fab")
		)
		(fp_line
			(start 0.12065 -0.2794)
			(end 0.12065 -0.3048)
			(stroke
				(width 0.1)
				(type default)
			)
			(layer "F.Fab")
		)
		(fp_line
			(start -0.12065 -0.2794)
			(end 0.12065 -0.2794)
			(stroke
				(width 0.1)
				(type default)
			)
			(layer "F.Fab")
		)
		(fp_line
			(start 0.120396 0.2794)
			(end -0.12065 0.2794)
			(stroke
				(width 0.1)
				(type default)
			)
			(layer "F.Fab")
		)
		(fp_line
			(start -0.12065 0.2794)
			(end -0.12065 0.3048)
			(stroke
				(width 0.1)
				(type default)
			)
			(layer "F.Fab")
		)
		(fp_line
			(start 0.67945 0.3048)
			(end 0.120396 0.3048)
			(stroke
				(width 0.1)
				(type default)
			)
			(layer "F.Fab")
		)
		(fp_line
			(start 0.120396 0.3048)
			(end 0.120396 0.2794)
			(stroke
				(width 0.1)
				(type default)
			)
			(layer "F.Fab")
		)
		(fp_line
			(start -0.12065 0.3048)
			(end -0.67945 0.3048)
			(stroke
				(width 0.1)
				(type default)
			)
			(layer "F.Fab")
		)
		(fp_line
			(start -0.67945 0.3048)
			(end -0.67945 -0.305054)
			(stroke
				(width 0.1)
				(type default)
			)
			(layer "F.Fab")
		)
		(pad "1" smd circle
			(at -0.40005 0 90)
			(size 0 0)
			(layers "F.Cu" "F.Mask" "F.Paste")
			(net "P3V3_AUX")
		)
		(pad "2" smd circle
			(at 0.40005 0 90)
			(size 0 0)
			(layers "F.Cu" "F.Mask" "F.Paste")
			(net "GND")
		)
	)
	(footprint ""
		(layer "F.Cu")
		(at 305.819048 -41.906698 180)
		(property "Reference" "R3670"
			(at 0 0 180)
			(layer "F.SilkS")
			(hide yes)
			(effects
				(font
					(size 1.27 1.27)
				)
			)
		)
		(property "Value" ""
			(at 0 0 180)
			(layer "F.Fab")
			(effects
				(font
					(size 1.27 1.27)
				)
			)
		)
		(duplicate_pad_numbers_are_jumpers no)
		(fp_line
			(start 0.7874 0.4064)
			(end -0.7874 0.4064)
			(stroke
				(width 0.1524)
				(type default)
			)
			(layer "F.SilkS")
		)
		(fp_line
			(start 0.7874 -0.4064)
			(end 0.7874 0.4064)
			(stroke
				(width 0.1524)
				(type default)
			)
			(layer "F.SilkS")
		)
		(fp_line
			(start -0.7874 0.4064)
			(end -0.7874 -0.4064)
			(stroke
				(width 0.1524)
				(type default)
			)
			(layer "F.SilkS")
		)
		(fp_line
			(start -0.7874 -0.4064)
			(end 0.7874 -0.4064)
			(stroke
				(width 0.1524)
				(type default)
			)
			(layer "F.SilkS")
		)
		(fp_line
			(start 0.67945 0.3048)
			(end 0.120396 0.3048)
			(stroke
				(width 0.1)
				(type default)
			)
			(layer "F.Fab")
		)
		(fp_line
			(start 0.67945 -0.3048)
			(end 0.67945 0.3048)
			(stroke
				(width 0.1)
				(type default)
			)
			(layer "F.Fab")
		)
		(fp_line
			(start 0.12065 -0.2794)
			(end 0.12065 -0.3048)
			(stroke
				(width 0.1)
				(type default)
			)
			(layer "F.Fab")
		)
		(fp_line
			(start 0.12065 -0.3048)
			(end 0.67945 -0.3048)
			(stroke
				(width 0.1)
				(type default)
			)
			(layer "F.Fab")
		)
		(fp_line
			(start 0.120396 0.3048)
			(end 0.120396 0.2794)
			(stroke
				(width 0.1)
				(type default)
			)
			(layer "F.Fab")
		)
		(fp_line
			(start 0.120396 0.2794)
			(end -0.12065 0.2794)
			(stroke
				(width 0.1)
				(type default)
			)
			(layer "F.Fab")
		)
		(fp_line
			(start -0.12065 0.3048)
			(end -0.67945 0.3048)
			(stroke
				(width 0.1)
				(type default)
			)
			(layer "F.Fab")
		)
		(fp_line
			(start -0.12065 0.2794)
			(end -0.12065 0.3048)
			(stroke
				(width 0.1)
				(type default)
			)
			(layer "F.Fab")
		)
		(fp_line
			(start -0.12065 -0.2794)
			(end 0.12065 -0.2794)
			(stroke
				(width 0.1)
				(type default)
			)
			(layer "F.Fab")
		)
		(fp_line
			(start -0.12065 -0.305054)
			(end -0.12065 -0.2794)
			(stroke
				(width 0.1)
				(type default)
			)
			(layer "F.Fab")
		)
		(fp_line
			(start -0.67945 0.3048)
			(end -0.67945 -0.305054)
			(stroke
				(width 0.1)
				(type default)
			)
			(layer "F.Fab")
		)
		(fp_line
			(start -0.67945 -0.305054)
			(end -0.12065 -0.305054)
			(stroke
				(width 0.1)
				(type default)
			)
			(layer "F.Fab")
		)
		(pad "1" smd circle
			(at -0.40005 0 180)
			(size 0 0)
			(layers "F.Cu" "F.Mask" "F.Paste")
			(net "ADC128_A0")
		)
		(pad "2" smd circle
			(at 0.40005 0 180)
			(size 0 0)
			(layers "F.Cu" "F.Mask" "F.Paste")
			(net "GND")
		)
	)
	(footprint ""
		(layer "F.Cu")
		(at 284.317694 -436.304436 90)
		(property "Reference" "R4553"
			(at 0 0 90)
			(layer "F.SilkS")
			(hide yes)
			(effects
				(font
					(size 1.27 1.27)
				)
			)
		)
		(property "Value" ""
			(at 0 0 90)
			(layer "F.Fab")
			(effects
				(font
					(size 1.27 1.27)
				)
			)
		)
		(duplicate_pad_numbers_are_jumpers no)
		(fp_line
			(start 0.7874 -0.4064)
			(end 0.7874 0.4064)
			(stroke
				(width 0.1524)
				(type default)
			)
			(layer "F.SilkS")
		)
		(fp_line
			(start -0.7874 -0.4064)
			(end 0.7874 -0.4064)
			(stroke
				(width 0.1524)
				(type default)
			)
			(layer "F.SilkS")
		)
		(fp_line
			(start 0.7874 0.4064)
			(end -0.7874 0.4064)
			(stroke
				(width 0.1524)
				(type default)
			)
			(layer "F.SilkS")
		)
		(fp_line
			(start -0.7874 0.4064)
			(end -0.7874 -0.4064)
			(stroke
				(width 0.1524)
				(type default)
			)
			(layer "F.SilkS")
		)
		(fp_line
			(start -0.12065 -0.305054)
			(end -0.12065 -0.2794)
			(stroke
				(width 0.1)
				(type default)
			)
			(layer "F.Fab")
		)
		(fp_line
			(start -0.67945 -0.305054)
			(end -0.12065 -0.305054)
			(stroke
				(width 0.1)
				(type default)
			)
			(layer "F.Fab")
		)
		(fp_line
			(start 0.67945 -0.3048)
			(end 0.67945 0.3048)
			(stroke
				(width 0.1)
				(type default)
			)
			(layer "F.Fab")
		)
		(fp_line
			(start 0.12065 -0.3048)
			(end 0.67945 -0.3048)
			(stroke
				(width 0.1)
				(type default)
			)
			(layer "F.Fab")
		)
		(fp_line
			(start 0.12065 -0.2794)
			(end 0.12065 -0.3048)
			(stroke
				(width 0.1)
				(type default)
			)
			(layer "F.Fab")
		)
		(fp_line
			(start -0.12065 -0.2794)
			(end 0.12065 -0.2794)
			(stroke
				(width 0.1)
				(type default)
			)
			(layer "F.Fab")
		)
		(fp_line
			(start 0.120396 0.2794)
			(end -0.12065 0.2794)
			(stroke
				(width 0.1)
				(type default)
			)
			(layer "F.Fab")
		)
		(fp_line
			(start -0.12065 0.2794)
			(end -0.12065 0.3048)
			(stroke
				(width 0.1)
				(type default)
			)
			(layer "F.Fab")
		)
		(fp_line
			(start 0.67945 0.3048)
			(end 0.120396 0.3048)
			(stroke
				(width 0.1)
				(type default)
			)
			(layer "F.Fab")
		)
		(fp_line
			(start 0.120396 0.3048)
			(end 0.120396 0.2794)
			(stroke
				(width 0.1)
				(type default)
			)
			(layer "F.Fab")
		)
		(fp_line
			(start -0.12065 0.3048)
			(end -0.67945 0.3048)
			(stroke
				(width 0.1)
				(type default)
			)
			(layer "F.Fab")
		)
		(fp_line
			(start -0.67945 0.3048)
			(end -0.67945 -0.305054)
			(stroke
				(width 0.1)
				(type default)
			)
			(layer "F.Fab")
		)
		(pad "1" smd circle
			(at -0.40005 0 90)
			(size 0 0)
			(layers "F.Cu" "F.Mask" "F.Paste")
			(net "P3V3_AUX")
		)
		(pad "2" smd circle
			(at 0.40005 0 90)
			(size 0 0)
			(layers "F.Cu" "F.Mask" "F.Paste")
			(net "HPDB_HSC_PWRGD_N")
		)
	)
	(footprint ""
		(layer "F.Cu")
		(at 180.772308 -165.292024 90)
		(property "Reference" "C1339"
			(at 0 0 90)
			(layer "F.SilkS")
			(hide yes)
			(effects
				(font
					(size 1.27 1.27)
				)
			)
		)
		(property "Value" ""
			(at 0 0 90)
			(layer "F.Fab")
			(effects
				(font
					(size 1.27 1.27)
				)
			)
		)
		(duplicate_pad_numbers_are_jumpers no)
		(fp_line
			(start 0.7874 -0.4064)
			(end 0.7874 0.4064)
			(stroke
				(width 0.1524)
				(type default)
			)
			(layer "F.SilkS")
		)
		(fp_line
			(start -0.7874 -0.4064)
			(end 0.7874 -0.4064)
			(stroke
				(width 0.1524)
				(type default)
			)
			(layer "F.SilkS")
		)
		(fp_line
			(start 0.7874 0.4064)
			(end -0.7874 0.4064)
			(stroke
				(width 0.1524)
				(type default)
			)
			(layer "F.SilkS")
		)
		(fp_line
			(start -0.7874 0.4064)
			(end -0.7874 -0.4064)
			(stroke
				(width 0.1524)
				(type default)
			)
			(layer "F.SilkS")
		)
		(fp_line
			(start -0.12065 -0.305054)
			(end -0.12065 -0.2794)
			(stroke
				(width 0.1)
				(type default)
			)
			(layer "F.Fab")
		)
		(fp_line
			(start -0.67945 -0.305054)
			(end -0.12065 -0.305054)
			(stroke
				(width 0.1)
				(type default)
			)
			(layer "F.Fab")
		)
		(fp_line
			(start 0.67945 -0.3048)
			(end 0.67945 0.3048)
			(stroke
				(width 0.1)
				(type default)
			)
			(layer "F.Fab")
		)
		(fp_line
			(start 0.12065 -0.3048)
			(end 0.67945 -0.3048)
			(stroke
				(width 0.1)
				(type default)
			)
			(layer "F.Fab")
		)
		(fp_line
			(start 0.12065 -0.2794)
			(end 0.12065 -0.3048)
			(stroke
				(width 0.1)
				(type default)
			)
			(layer "F.Fab")
		)
		(fp_line
			(start -0.12065 -0.2794)
			(end 0.12065 -0.2794)
			(stroke
				(width 0.1)
				(type default)
			)
			(layer "F.Fab")
		)
		(fp_line
			(start 0.120396 0.2794)
			(end -0.12065 0.2794)
			(stroke
				(width 0.1)
				(type default)
			)
			(layer "F.Fab")
		)
		(fp_line
			(start -0.12065 0.2794)
			(end -0.12065 0.3048)
			(stroke
				(width 0.1)
				(type default)
			)
			(layer "F.Fab")
		)
		(fp_line
			(start 0.67945 0.3048)
			(end 0.120396 0.3048)
			(stroke
				(width 0.1)
				(type default)
			)
			(layer "F.Fab")
		)
		(fp_line
			(start 0.120396 0.3048)
			(end 0.120396 0.2794)
			(stroke
				(width 0.1)
				(type default)
			)
			(layer "F.Fab")
		)
		(fp_line
			(start -0.12065 0.3048)
			(end -0.67945 0.3048)
			(stroke
				(width 0.1)
				(type default)
			)
			(layer "F.Fab")
		)
		(fp_line
			(start -0.67945 0.3048)
			(end -0.67945 -0.305054)
			(stroke
				(width 0.1)
				(type default)
			)
			(layer "F.Fab")
		)
		(pad "1" smd circle
			(at -0.40005 0 90)
			(size 0 0)
			(layers "F.Cu" "F.Mask" "F.Paste")
			(net "P3V3_AUX")
		)
		(pad "2" smd circle
			(at 0.40005 0 90)
			(size 0 0)
			(layers "F.Cu" "F.Mask" "F.Paste")
			(net "GND")
		)
	)
)
